#ISCELL
  logical_power cad_note *
  *
#ISCELL
  pure_quanta quanta_title_block_c *
  *
#ISCELL
  standard offpage *
  page95_i1
#ISCELL
  standard offpage *
  page95_i10
#ISCELL
  standard tap *
  page95_i100
#ISCELL
  standard tap *
  page95_i101
#ISCELL
  standard tap *
  page95_i102
#ISCELL
  standard tap *
  page95_i103
#ISCELL
  standard tap *
  page95_i104
#ISCELL
  standard offpage *
  page95_i105
#ISCELL
  standard tap *
  page95_i106
#ISCELL
  standard tap *
  page95_i107
#ISCELL
  standard tap *
  page95_i108
#ISCELL
  standard tap *
  page95_i109
#ISCELL
  standard offpage *
  page95_i11
#ISCELL
  standard tap *
  page95_i110
#ISCELL
  standard tap *
  page95_i111
#ISCELL
  standard tap *
  page95_i112
#ISCELL
  standard tap *
  page95_i113
#ISCELL
  standard tap *
  page95_i114
#ISCELL
  standard tap *
  page95_i115
#ISCELL
  standard tap *
  page95_i116
#ISCELL
  standard tap *
  page95_i117
#ISCELL
  standard tap *
  page95_i118
#ISCELL
  standard tap *
  page95_i119
#ISCELL
  standard offpage *
  page95_i12
#ISCELL
  logical_power universal_gnd *
  page95_i120
#CELL
  pure_quanta q_cap *
  page95_i121
#ISCELL
  logical_power vcc_core *
  page95_i122
#ISCELL
  standard offpage *
  page95_i123
#CELL
  pure_quanta q_cap *
  page95_i125
#ISCELL
  logical_power vcc_core *
  page95_i126
#ISCELL
  logical_power universal_gnd *
  page95_i127
#CELL
  pure_quanta q_cap *
  page95_i128
#ISCELL
  logical_power universal_gnd *
  page95_i129
#ISCELL
  standard offpage *
  page95_i13
#ISCELL
  standard tap *
  page95_i130
#ISCELL
  standard tap *
  page95_i131
#ISCELL
  standard tap *
  page95_i132
#ISCELL
  standard tap *
  page95_i133
#ISCELL
  standard tap *
  page95_i134
#ISCELL
  standard tap *
  page95_i135
#ISCELL
  standard tap *
  page95_i136
#ISCELL
  standard tap *
  page95_i137
#ISCELL
  standard tap *
  page95_i138
#ISCELL
  standard tap *
  page95_i139
#ISCELL
  standard offpage *
  page95_i14
#ISCELL
  standard tap *
  page95_i140
#ISCELL
  standard tap *
  page95_i141
#ISCELL
  standard tap *
  page95_i142
#ISCELL
  standard tap *
  page95_i143
#ISCELL
  standard tap *
  page95_i144
#ISCELL
  standard tap *
  page95_i145
#ISCELL
  standard tap *
  page95_i146
#ISCELL
  standard tap *
  page95_i147
#ISCELL
  standard tap *
  page95_i148
#ISCELL
  standard tap *
  page95_i149
#ISCELL
  standard offpage *
  page95_i15
#ISCELL
  standard tap *
  page95_i150
#ISCELL
  standard tap *
  page95_i151
#ISCELL
  standard tap *
  page95_i152
#ISCELL
  standard tap *
  page95_i153
#ISCELL
  standard tap *
  page95_i154
#ISCELL
  standard tap *
  page95_i155
#ISCELL
  standard tap *
  page95_i156
#ISCELL
  standard tap *
  page95_i157
#ISCELL
  standard tap *
  page95_i158
#ISCELL
  standard tap *
  page95_i159
#ISCELL
  standard offpage *
  page95_i16
#ISCELL
  standard tap *
  page95_i160
#ISCELL
  standard tap *
  page95_i161
#ISCELL
  standard tap *
  page95_i162
#ISCELL
  standard offpage *
  page95_i163
#ISCELL
  standard offpage *
  page95_i164
#ISCELL
  standard offpage *
  page95_i165
#ISCELL
  standard tap *
  page95_i166
#ISCELL
  standard tap *
  page95_i167
#ISCELL
  standard tap *
  page95_i168
#ISCELL
  standard tap *
  page95_i169
#ISCELL
  standard offpage *
  page95_i17
#ISCELL
  standard tap *
  page95_i170
#ISCELL
  standard tap *
  page95_i171
#ISCELL
  standard tap *
  page95_i172
#ISCELL
  standard offpage *
  page95_i173
#ISCELL
  standard offpage *
  page95_i174
#ISCELL
  logical_power vcc_core *
  page95_i175
#CELL
  pure_quanta sconn288_adr50017p087cc *
  page95_i176
#ISCELL
  logical_power universal_gnd *
  page95_i177
#CELL
  pure_quanta sconn288_adr50017p087cc *
  page95_i178
#CELL
  pure_quanta q_res *
  page95_i179
#ISCELL
  standard offpage *
  page95_i18
#ISCELL
  standard offpage *
  page95_i180
#ISCELL
  standard offpage *
  page95_i19
#ISCELL
  standard offpage *
  page95_i2
#ISCELL
  standard offpage *
  page95_i20
#ISCELL
  logical_power vcc_core *
  page95_i21
#ISCELL
  standard tap *
  page95_i22
#ISCELL
  standard tap *
  page95_i23
#ISCELL
  standard tap *
  page95_i24
#ISCELL
  standard tap *
  page95_i25
#ISCELL
  standard tap *
  page95_i26
#ISCELL
  standard tap *
  page95_i27
#ISCELL
  standard tap *
  page95_i28
#ISCELL
  standard tap *
  page95_i29
#ISCELL
  standard offpage *
  page95_i3
#ISCELL
  standard tap *
  page95_i30
#ISCELL
  standard tap *
  page95_i31
#ISCELL
  standard tap *
  page95_i32
#ISCELL
  standard tap *
  page95_i33
#ISCELL
  standard tap *
  page95_i34
#ISCELL
  standard tap *
  page95_i35
#ISCELL
  standard tap *
  page95_i36
#ISCELL
  standard tap *
  page95_i37
#ISCELL
  standard tap *
  page95_i38
#ISCELL
  standard tap *
  page95_i39
#ISCELL
  standard offpage *
  page95_i4
#ISCELL
  standard tap *
  page95_i40
#ISCELL
  standard tap *
  page95_i41
#ISCELL
  standard tap *
  page95_i42
#ISCELL
  standard tap *
  page95_i43
#ISCELL
  standard tap *
  page95_i44
#ISCELL
  logical_power universal_gnd *
  page95_i45
#CELL
  pure_quanta q_res *
  page95_i46
#CELL
  pure_quanta sconn288_adr50017p087cc *
  page95_i47
#ISCELL
  standard tap *
  page95_i48
#ISCELL
  standard tap *
  page95_i49
#ISCELL
  standard tap *
  page95_i50
#ISCELL
  standard tap *
  page95_i51
#ISCELL
  standard tap *
  page95_i52
#ISCELL
  standard tap *
  page95_i53
#ISCELL
  standard tap *
  page95_i54
#ISCELL
  standard tap *
  page95_i55
#ISCELL
  standard tap *
  page95_i56
#ISCELL
  standard tap *
  page95_i57
#ISCELL
  standard tap *
  page95_i58
#ISCELL
  standard tap *
  page95_i59
#ISCELL
  standard offpage *
  page95_i6
#ISCELL
  standard tap *
  page95_i60
#ISCELL
  standard tap *
  page95_i61
#ISCELL
  standard tap *
  page95_i62
#ISCELL
  standard tap *
  page95_i63
#ISCELL
  standard tap *
  page95_i64
#ISCELL
  standard tap *
  page95_i65
#ISCELL
  standard tap *
  page95_i66
#ISCELL
  standard tap *
  page95_i67
#ISCELL
  standard tap *
  page95_i68
#ISCELL
  standard tap *
  page95_i69
#ISCELL
  standard offpage *
  page95_i7
#ISCELL
  standard tap *
  page95_i70
#ISCELL
  standard tap *
  page95_i71
#ISCELL
  standard tap *
  page95_i72
#ISCELL
  standard tap *
  page95_i73
#ISCELL
  standard tap *
  page95_i74
#ISCELL
  standard tap *
  page95_i75
#ISCELL
  standard tap *
  page95_i76
#ISCELL
  standard tap *
  page95_i77
#ISCELL
  standard tap *
  page95_i78
#ISCELL
  standard tap *
  page95_i79
#ISCELL
  standard offpage *
  page95_i8
#ISCELL
  standard tap *
  page95_i80
#ISCELL
  standard tap *
  page95_i81
#ISCELL
  standard tap *
  page95_i82
#ISCELL
  standard tap *
  page95_i83
#ISCELL
  standard tap *
  page95_i84
#ISCELL
  standard tap *
  page95_i85
#ISCELL
  standard tap *
  page95_i86
#ISCELL
  standard tap *
  page95_i87
#ISCELL
  standard tap *
  page95_i88
#ISCELL
  standard tap *
  page95_i89
#ISCELL
  standard offpage *
  page95_i9
#ISCELL
  standard tap *
  page95_i90
#ISCELL
  standard tap *
  page95_i91
#ISCELL
  standard tap *
  page95_i92
#ISCELL
  standard tap *
  page95_i93
#ISCELL
  standard tap *
  page95_i94
#ISCELL
  standard tap *
  page95_i95
#ISCELL
  standard tap *
  page95_i96
#ISCELL
  standard tap *
  page95_i97
#ISCELL
  standard tap *
  page95_i98
#ISCELL
  standard tap *
  page95_i99
